(kicad_pcb
	(version 20260206)
	(generator "pcbnew")
	(generator_version "10.0")
	(general
		(thickness 1.6)
		(legacy_teardrops no)
	)
	(paper "A4")
	(title_block
		(title "v2-pdb — ms_pdb_v2.brd")
		(comment 1 "Open CloudServer (Microsoft) / footprint 293 of 348 (J26), pads 79-156 of 166")
	)
	(layers
		(0 "F.Cu" signal "TOP")
		(4 "In1.Cu" signal "GND")
		(6 "In2.Cu" signal "IN1")
		(8 "In3.Cu" signal "VCC")
		(10 "In4.Cu" signal "VCC1")
		(12 "In5.Cu" signal "IN2")
		(14 "In6.Cu" signal "GND1")
		(2 "B.Cu" signal "BOTTOM")
		(9 "F.Adhes" user "F.Adhesive")
		(11 "B.Adhes" user "B.Adhesive")
		(13 "F.Paste" user "Package Geometry/Pastemask Top")
		(15 "B.Paste" user "Package Geometry/Pastemask Bottom")
		(5 "F.SilkS" user "Ref Des/Silkscreen Top")
		(7 "B.SilkS" user "Ref Des/Silkscreen Bottom")
		(1 "F.Mask" user "Board Geometry/Soldermask Top")
		(3 "B.Mask" user "Board Geometry/Soldermask Bottom")
		(17 "Dwgs.User" user "User.Drawings")
		(19 "Cmts.User" user "User.Comments")
		(21 "Eco1.User" user "User.Eco1")
		(23 "Eco2.User" user "User.Eco2")
		(25 "Edge.Cuts" user "Board Geometry/Outline")
		(27 "Margin" user)
		(31 "F.CrtYd" user "Package Geometry/Place Bound Top")
		(29 "B.CrtYd" user "Package Geometry/Place Bound Bottom")
		(35 "F.Fab" user "Ref Des/Assembly Top")
		(33 "B.Fab" user "Ref Des/Assembly Bottom")
	)
	(footprint ""
		(layer "F.Cu")
		(at 6.448806 -261.670546)
		(property "Reference" "J26"
			(at 6.660642 8.995918 90)
			(unlocked yes)
			(layer "F.SilkS")
			(effects
				(font
					(size 0.7874 0.5842)
					(thickness 0.1524)
				)
				(justify left)
			)
		)
		(property "Value" ""
			(at 0 0 0)
			(layer "F.Fab")
			(effects
				(font
					(size 1.27 1.27)
				)
			)
		)
		(duplicate_pad_numbers_are_jumpers no)
		(pad "A77" thru_hole circle
			(at 0 78.000098 270)
			(size 1.016 1.016)
			(drill 0.7112)
			(layers "*.Cu" "*.Mask")
			(remove_unused_layers no)
			(net "GND")
			(clearance 0.1016)
			(thermal_gap 0.1016)
		)
		(pad "A78" thru_hole circle
			(at 1.999996 79.000096 270)
			(size 1.016 1.016)
			(drill 0.7112)
			(layers "*.Cu" "*.Mask")
			(remove_unused_layers no)
			(net "P12V")
			(clearance 0.1016)
			(thermal_gap 0.1016)
		)
		(pad "A79" thru_hole circle
			(at 0 80.000094 270)
			(size 1.016 1.016)
			(drill 0.7112)
			(layers "*.Cu" "*.Mask")
			(remove_unused_layers no)
			(net "P12V")
			(clearance 0.1016)
			(thermal_gap 0.1016)
		)
		(pad "A80" thru_hole circle
			(at 1.999996 81.000092 270)
			(size 1.016 1.016)
			(drill 0.7112)
			(layers "*.Cu" "*.Mask")
			(remove_unused_layers no)
			(net "P12V")
			(clearance 0.1016)
			(thermal_gap 0.1016)
		)
		(pad "A81" thru_hole circle
			(at 0 82.00009 270)
			(size 1.016 1.016)
			(drill 0.7112)
			(layers "*.Cu" "*.Mask")
			(remove_unused_layers no)
			(net "P12V")
			(clearance 0.1016)
			(thermal_gap 0.1016)
		)
		(pad "A82" thru_hole circle
			(at 1.999996 83.000088 270)
			(size 1.016 1.016)
			(drill 0.7112)
			(layers "*.Cu" "*.Mask")
			(remove_unused_layers no)
			(net "P12V")
			(clearance 0.1016)
			(thermal_gap 0.1016)
		)
		(pad "B1" thru_hole circle
			(at -2.499868 0 270)
			(size 1.016 1.016)
			(drill 0.7112)
			(layers "*.Cu" "*.Mask")
			(remove_unused_layers no)
			(net "GND")
			(clearance 0.1016)
			(thermal_gap 0.1016)
		)
		(pad "B2" thru_hole circle
			(at -4.499864 0.999998 270)
			(size 1.016 1.016)
			(drill 0.7112)
			(layers "*.Cu" "*.Mask")
			(remove_unused_layers no)
			(net "T6_BLAD2_RXD")
			(clearance 0.1016)
			(thermal_gap 0.1016)
		)
		(pad "B3" thru_hole circle
			(at -2.499868 1.999996 270)
			(size 1.016 1.016)
			(drill 0.7112)
			(layers "*.Cu" "*.Mask")
			(remove_unused_layers no)
			(net "T6_BLAD2_TXD")
			(clearance 0.1016)
			(thermal_gap 0.1016)
		)
		(pad "B4" thru_hole circle
			(at -4.499864 2.999994 270)
			(size 1.016 1.016)
			(drill 0.7112)
			(layers "*.Cu" "*.Mask")
			(remove_unused_layers no)
			(net "GND")
			(clearance 0.1016)
			(thermal_gap 0.1016)
		)
		(pad "B5" thru_hole circle
			(at -2.499868 3.999992 270)
			(size 1.016 1.016)
			(drill 0.7112)
			(layers "*.Cu" "*.Mask")
			(remove_unused_layers no)
			(net "T6_BLAD3_RXD")
			(clearance 0.1016)
			(thermal_gap 0.1016)
		)
		(pad "B6" thru_hole circle
			(at -4.499864 4.99999 270)
			(size 1.016 1.016)
			(drill 0.7112)
			(layers "*.Cu" "*.Mask")
			(remove_unused_layers no)
			(net "T6_BLAD3_TXD")
			(clearance 0.1016)
			(thermal_gap 0.1016)
		)
		(pad "B7" thru_hole circle
			(at -2.499868 5.999988 270)
			(size 1.016 1.016)
			(drill 0.7112)
			(layers "*.Cu" "*.Mask")
			(remove_unused_layers no)
			(net "T6_BLAD4_RXD")
			(clearance 0.1016)
			(thermal_gap 0.1016)
		)
		(pad "B8" thru_hole circle
			(at -4.499864 6.999986 270)
			(size 1.016 1.016)
			(drill 0.7112)
			(layers "*.Cu" "*.Mask")
			(remove_unused_layers no)
			(net "T6_BLAD4_TXD")
			(clearance 0.1016)
			(thermal_gap 0.1016)
		)
		(pad "B9" thru_hole circle
			(at -2.499868 7.999984 270)
			(size 1.016 1.016)
			(drill 0.7112)
			(layers "*.Cu" "*.Mask")
			(remove_unused_layers no)
			(net "GND")
			(clearance 0.1016)
			(thermal_gap 0.1016)
		)
		(pad "B10" thru_hole circle
			(at -4.499864 8.999982 270)
			(size 1.016 1.016)
			(drill 0.7112)
			(layers "*.Cu" "*.Mask")
			(remove_unused_layers no)
			(net "I2C_PSU2_SCL")
			(clearance 0.1016)
			(thermal_gap 0.1016)
		)
		(pad "B11" thru_hole circle
			(at -2.499868 9.99998 270)
			(size 1.016 1.016)
			(drill 0.7112)
			(layers "*.Cu" "*.Mask")
			(remove_unused_layers no)
			(net "I2C_PSU2_SDA")
			(clearance 0.1016)
			(thermal_gap 0.1016)
		)
		(pad "B12" thru_hole circle
			(at -4.499864 12.999974 270)
			(size 1.016 1.016)
			(drill 0.7112)
			(layers "*.Cu" "*.Mask")
			(remove_unused_layers no)
			(net "T4_BLAD1_EN")
			(clearance 0.1016)
			(thermal_gap 0.1016)
		)
		(pad "B13" thru_hole circle
			(at -2.499868 13.999972 270)
			(size 1.016 1.016)
			(drill 0.7112)
			(layers "*.Cu" "*.Mask")
			(remove_unused_layers no)
			(net "TP_T4_BLAD2_EN")
			(clearance 0.1016)
			(thermal_gap 0.1016)
		)
		(pad "B14" thru_hole circle
			(at -4.499864 14.99997 270)
			(size 1.016 1.016)
			(drill 0.7112)
			(layers "*.Cu" "*.Mask")
			(remove_unused_layers no)
			(net "T4_BLAD3_EN")
			(clearance 0.1016)
			(thermal_gap 0.1016)
		)
		(pad "B15" thru_hole circle
			(at -2.499868 15.999968 270)
			(size 1.016 1.016)
			(drill 0.7112)
			(layers "*.Cu" "*.Mask")
			(remove_unused_layers no)
			(net "TP_T4_BLAD4_EN")
			(clearance 0.1016)
			(thermal_gap 0.1016)
		)
		(pad "B16" thru_hole circle
			(at -4.499864 16.999966 270)
			(size 1.016 1.016)
			(drill 0.7112)
			(layers "*.Cu" "*.Mask")
			(remove_unused_layers no)
			(net "GND")
			(clearance 0.1016)
			(thermal_gap 0.1016)
		)
		(pad "B17" thru_hole circle
			(at -2.499868 17.999964 270)
			(size 1.016 1.016)
			(drill 0.7112)
			(layers "*.Cu" "*.Mask")
			(remove_unused_layers no)
			(net "T4_BLAD1_RXD")
			(clearance 0.1016)
			(thermal_gap 0.1016)
		)
		(pad "B18" thru_hole circle
			(at -4.499864 18.999962 270)
			(size 1.016 1.016)
			(drill 0.7112)
			(layers "*.Cu" "*.Mask")
			(remove_unused_layers no)
			(net "T4_BLAD1_TXD")
			(clearance 0.1016)
			(thermal_gap 0.1016)
		)
		(pad "B19" thru_hole circle
			(at -2.499868 19.99996 270)
			(size 1.016 1.016)
			(drill 0.7112)
			(layers "*.Cu" "*.Mask")
			(remove_unused_layers no)
			(net "T4_BLAD2_RXD")
			(clearance 0.1016)
			(thermal_gap 0.1016)
		)
		(pad "B20" thru_hole circle
			(at -4.499864 20.999958 270)
			(size 1.016 1.016)
			(drill 0.7112)
			(layers "*.Cu" "*.Mask")
			(remove_unused_layers no)
			(net "T4_BLAD2_TXD")
			(clearance 0.1016)
			(thermal_gap 0.1016)
		)
		(pad "B21" thru_hole circle
			(at -2.499868 21.999956 270)
			(size 1.016 1.016)
			(drill 0.7112)
			(layers "*.Cu" "*.Mask")
			(remove_unused_layers no)
			(net "GND")
			(clearance 0.1016)
			(thermal_gap 0.1016)
		)
		(pad "B22" thru_hole circle
			(at -4.499864 22.999954 270)
			(size 1.016 1.016)
			(drill 0.7112)
			(layers "*.Cu" "*.Mask")
			(remove_unused_layers no)
			(net "T4_BLAD3_RXD")
			(clearance 0.1016)
			(thermal_gap 0.1016)
		)
		(pad "B23" thru_hole circle
			(at -2.499868 23.999952 270)
			(size 1.016 1.016)
			(drill 0.7112)
			(layers "*.Cu" "*.Mask")
			(remove_unused_layers no)
			(net "T4_BLAD3_TXD")
			(clearance 0.1016)
			(thermal_gap 0.1016)
		)
		(pad "B24" thru_hole circle
			(at -4.499864 24.99995 270)
			(size 1.016 1.016)
			(drill 0.7112)
			(layers "*.Cu" "*.Mask")
			(remove_unused_layers no)
			(net "T4_BLAD4_RXD")
			(clearance 0.1016)
			(thermal_gap 0.1016)
		)
		(pad "B25" thru_hole circle
			(at -2.499868 25.999948 270)
			(size 1.016 1.016)
			(drill 0.7112)
			(layers "*.Cu" "*.Mask")
			(remove_unused_layers no)
			(net "T4_BLAD4_TXD")
			(clearance 0.1016)
			(thermal_gap 0.1016)
		)
		(pad "B26" thru_hole circle
			(at -4.499864 26.999946 270)
			(size 1.016 1.016)
			(drill 0.7112)
			(layers "*.Cu" "*.Mask")
			(remove_unused_layers no)
			(net "GND")
			(clearance 0.1016)
			(thermal_gap 0.1016)
		)
		(pad "B27" thru_hole circle
			(at -2.499868 27.999944 270)
			(size 1.016 1.016)
			(drill 0.7112)
			(layers "*.Cu" "*.Mask")
			(remove_unused_layers no)
			(net "T2_BLAD1_EN")
			(clearance 0.1016)
			(thermal_gap 0.1016)
		)
		(pad "B28" thru_hole circle
			(at -4.499864 28.999942 270)
			(size 1.016 1.016)
			(drill 0.7112)
			(layers "*.Cu" "*.Mask")
			(remove_unused_layers no)
			(net "TP_T2_BLAD2_EN")
			(clearance 0.1016)
			(thermal_gap 0.1016)
		)
		(pad "B29" thru_hole circle
			(at -2.499868 29.99994 270)
			(size 1.016 1.016)
			(drill 0.7112)
			(layers "*.Cu" "*.Mask")
			(remove_unused_layers no)
			(net "T2_BLAD3_EN")
			(clearance 0.1016)
			(thermal_gap 0.1016)
		)
		(pad "B30" thru_hole circle
			(at -4.499864 30.999938 270)
			(size 1.016 1.016)
			(drill 0.7112)
			(layers "*.Cu" "*.Mask")
			(remove_unused_layers no)
			(net "TP_T2_BLAD4_EN")
			(clearance 0.1016)
			(thermal_gap 0.1016)
		)
		(pad "B31" thru_hole circle
			(at -2.499868 31.999936 270)
			(size 1.016 1.016)
			(drill 0.7112)
			(layers "*.Cu" "*.Mask")
			(remove_unused_layers no)
			(net "GND")
			(clearance 0.1016)
			(thermal_gap 0.1016)
		)
		(pad "B32" thru_hole circle
			(at -4.499864 32.999934 270)
			(size 1.016 1.016)
			(drill 0.7112)
			(layers "*.Cu" "*.Mask")
			(remove_unused_layers no)
			(net "T2_BLAD1_RXD")
			(clearance 0.1016)
			(thermal_gap 0.1016)
		)
		(pad "B33" thru_hole circle
			(at -2.499868 33.999932 270)
			(size 1.016 1.016)
			(drill 0.7112)
			(layers "*.Cu" "*.Mask")
			(remove_unused_layers no)
			(net "T2_BLAD1_TXD")
			(clearance 0.1016)
			(thermal_gap 0.1016)
		)
		(pad "B34" thru_hole circle
			(at -4.499864 34.99993 270)
			(size 1.016 1.016)
			(drill 0.7112)
			(layers "*.Cu" "*.Mask")
			(remove_unused_layers no)
			(net "T2_BLAD2_RXD")
			(clearance 0.1016)
			(thermal_gap 0.1016)
		)
		(pad "B35" thru_hole circle
			(at -2.499868 35.999928 270)
			(size 1.016 1.016)
			(drill 0.7112)
			(layers "*.Cu" "*.Mask")
			(remove_unused_layers no)
			(net "T2_BLAD2_TXD")
			(clearance 0.1016)
			(thermal_gap 0.1016)
		)
		(pad "B36" thru_hole circle
			(at -4.499864 36.999926 270)
			(size 1.016 1.016)
			(drill 0.7112)
			(layers "*.Cu" "*.Mask")
			(remove_unused_layers no)
			(net "GND")
			(clearance 0.1016)
			(thermal_gap 0.1016)
		)
		(pad "B37" thru_hole circle
			(at -2.499868 37.999924 270)
			(size 1.016 1.016)
			(drill 0.7112)
			(layers "*.Cu" "*.Mask")
			(remove_unused_layers no)
			(net "T2_BLAD3_RXD")
			(clearance 0.1016)
			(thermal_gap 0.1016)
		)
		(pad "B38" thru_hole circle
			(at -4.499864 38.999922 270)
			(size 1.016 1.016)
			(drill 0.7112)
			(layers "*.Cu" "*.Mask")
			(remove_unused_layers no)
			(net "T2_BLAD3_TXD")
			(clearance 0.1016)
			(thermal_gap 0.1016)
		)
		(pad "B39" thru_hole circle
			(at -2.499868 39.99992 270)
			(size 1.016 1.016)
			(drill 0.7112)
			(layers "*.Cu" "*.Mask")
			(remove_unused_layers no)
			(net "T2_BLAD4_RXD")
			(clearance 0.1016)
			(thermal_gap 0.1016)
		)
		(pad "B40" thru_hole circle
			(at -4.499864 40.999918 270)
			(size 1.016 1.016)
			(drill 0.7112)
			(layers "*.Cu" "*.Mask")
			(remove_unused_layers no)
			(net "T2_BLAD4_TXD")
			(clearance 0.1016)
			(thermal_gap 0.1016)
		)
		(pad "B41" thru_hole circle
			(at -2.499868 41.999916 270)
			(size 1.016 1.016)
			(drill 0.7112)
			(layers "*.Cu" "*.Mask")
			(remove_unused_layers no)
			(net "GND")
			(clearance 0.1016)
			(thermal_gap 0.1016)
		)
		(pad "B42" thru_hole circle
			(at -4.499864 42.999914 270)
			(size 1.016 1.016)
			(drill 0.7112)
			(layers "*.Cu" "*.Mask")
			(remove_unused_layers no)
			(net "I2C_PSU1_SCL")
			(clearance 0.1016)
			(thermal_gap 0.1016)
		)
		(pad "B43" thru_hole circle
			(at -2.499868 43.999912 270)
			(size 1.016 1.016)
			(drill 0.7112)
			(layers "*.Cu" "*.Mask")
			(remove_unused_layers no)
			(net "I2C_PSU1_SDA")
			(clearance 0.1016)
			(thermal_gap 0.1016)
		)
		(pad "B44" thru_hole circle
			(at -4.499864 44.99991 270)
			(size 1.016 1.016)
			(drill 0.7112)
			(layers "*.Cu" "*.Mask")
			(remove_unused_layers no)
			(net "GND")
			(clearance 0.1016)
			(thermal_gap 0.1016)
		)
		(pad "B45" thru_hole circle
			(at -2.499868 45.999908 270)
			(size 1.016 1.016)
			(drill 0.7112)
			(layers "*.Cu" "*.Mask")
			(remove_unused_layers no)
			(net "PSU1_AC_OK")
			(clearance 0.1016)
			(thermal_gap 0.1016)
		)
		(pad "B46" thru_hole circle
			(at -4.499864 46.999906 270)
			(size 1.016 1.016)
			(drill 0.7112)
			(layers "*.Cu" "*.Mask")
			(remove_unused_layers no)
			(net "PSU2_AC_OK")
			(clearance 0.1016)
			(thermal_gap 0.1016)
		)
		(pad "B47" thru_hole circle
			(at -2.499868 47.999904 270)
			(size 1.016 1.016)
			(drill 0.7112)
			(layers "*.Cu" "*.Mask")
			(remove_unused_layers no)
			(net "PSU3_AC_OK")
			(clearance 0.1016)
			(thermal_gap 0.1016)
		)
		(pad "B48" thru_hole circle
			(at -4.499864 48.999902 270)
			(size 1.016 1.016)
			(drill 0.7112)
			(layers "*.Cu" "*.Mask")
			(remove_unused_layers no)
			(net "PSU4_AC_OK")
			(clearance 0.1016)
			(thermal_gap 0.1016)
		)
		(pad "B49" thru_hole circle
			(at -2.499868 49.9999 270)
			(size 1.016 1.016)
			(drill 0.7112)
			(layers "*.Cu" "*.Mask")
			(remove_unused_layers no)
			(net "PSU5_AC_OK")
			(clearance 0.1016)
			(thermal_gap 0.1016)
		)
		(pad "B50" thru_hole circle
			(at -4.499864 50.999898 270)
			(size 1.016 1.016)
			(drill 0.7112)
			(layers "*.Cu" "*.Mask")
			(remove_unused_layers no)
			(net "PSU6_AC_OK")
			(clearance 0.1016)
			(thermal_gap 0.1016)
		)
		(pad "B51" thru_hole circle
			(at -2.499868 51.999896 270)
			(size 1.016 1.016)
			(drill 0.7112)
			(layers "*.Cu" "*.Mask")
			(remove_unused_layers no)
			(net "GND")
			(clearance 0.1016)
			(thermal_gap 0.1016)
		)
		(pad "B52" thru_hole circle
			(at -4.499864 52.999894 270)
			(size 1.016 1.016)
			(drill 0.7112)
			(layers "*.Cu" "*.Mask")
			(remove_unused_layers no)
			(net "UART_RTS_P5_L_N")
			(clearance 0.1016)
			(thermal_gap 0.1016)
		)
		(pad "B53" thru_hole circle
			(at -2.499868 53.999892 270)
			(size 1.016 1.016)
			(drill 0.7112)
			(layers "*.Cu" "*.Mask")
			(remove_unused_layers no)
			(net "UART_DSR_P5_L_N")
			(clearance 0.1016)
			(thermal_gap 0.1016)
		)
		(pad "B54" thru_hole circle
			(at -4.499864 54.99989 270)
			(size 1.016 1.016)
			(drill 0.7112)
			(layers "*.Cu" "*.Mask")
			(remove_unused_layers no)
			(net "UART_RX_P5_L")
			(clearance 0.1016)
			(thermal_gap 0.1016)
		)
		(pad "B55" thru_hole circle
			(at -2.499868 55.999888 270)
			(size 1.016 1.016)
			(drill 0.7112)
			(layers "*.Cu" "*.Mask")
			(remove_unused_layers no)
			(net "UART_TX_P5_L")
			(clearance 0.1016)
			(thermal_gap 0.1016)
		)
		(pad "B56" thru_hole circle
			(at -4.499864 56.999886 270)
			(size 1.016 1.016)
			(drill 0.7112)
			(layers "*.Cu" "*.Mask")
			(remove_unused_layers no)
			(net "UART_DTR_P5_L_N")
			(clearance 0.1016)
			(thermal_gap 0.1016)
		)
		(pad "B57" thru_hole circle
			(at -2.499868 57.999884 270)
			(size 1.016 1.016)
			(drill 0.7112)
			(layers "*.Cu" "*.Mask")
			(remove_unused_layers no)
			(net "UART_CTS_P5_L_N")
			(clearance 0.1016)
			(thermal_gap 0.1016)
		)
		(pad "B58" thru_hole circle
			(at -4.499864 59.000136 270)
			(size 1.016 1.016)
			(drill 0.7112)
			(layers "*.Cu" "*.Mask")
			(remove_unused_layers no)
			(net "UART_RI_P5_L_N")
			(clearance 0.1016)
			(thermal_gap 0.1016)
		)
		(pad "B59" thru_hole circle
			(at -2.499868 59.99988 270)
			(size 1.016 1.016)
			(drill 0.7112)
			(layers "*.Cu" "*.Mask")
			(remove_unused_layers no)
			(net "GND")
			(clearance 0.1016)
			(thermal_gap 0.1016)
		)
		(pad "B60" thru_hole circle
			(at -4.499864 61.000132 270)
			(size 1.016 1.016)
			(drill 0.7112)
			(layers "*.Cu" "*.Mask")
			(remove_unused_layers no)
			(net "UART_RTS_P1_L_N")
			(clearance 0.1016)
			(thermal_gap 0.1016)
		)
		(pad "B61" thru_hole circle
			(at -2.499868 61.999876 270)
			(size 1.016 1.016)
			(drill 0.7112)
			(layers "*.Cu" "*.Mask")
			(remove_unused_layers no)
			(net "UART_DSR_P1_L_N")
			(clearance 0.1016)
			(thermal_gap 0.1016)
		)
		(pad "B62" thru_hole circle
			(at -4.499864 63.000128 270)
			(size 1.016 1.016)
			(drill 0.7112)
			(layers "*.Cu" "*.Mask")
			(remove_unused_layers no)
			(net "UART_RX_P1_L")
			(clearance 0.1016)
			(thermal_gap 0.1016)
		)
		(pad "B63" thru_hole circle
			(at -2.499868 63.999872 270)
			(size 1.016 1.016)
			(drill 0.7112)
			(layers "*.Cu" "*.Mask")
			(remove_unused_layers no)
			(net "UART_TX_P1_L")
			(clearance 0.1016)
			(thermal_gap 0.1016)
		)
		(pad "B64" thru_hole circle
			(at -4.499864 65.000124 270)
			(size 1.016 1.016)
			(drill 0.7112)
			(layers "*.Cu" "*.Mask")
			(remove_unused_layers no)
			(net "UART_DTR_P1_L_N")
			(clearance 0.1016)
			(thermal_gap 0.1016)
		)
		(pad "B65" thru_hole circle
			(at -2.499868 65.999868 270)
			(size 1.016 1.016)
			(drill 0.7112)
			(layers "*.Cu" "*.Mask")
			(remove_unused_layers no)
			(net "UART_CTS_P1_L_N")
			(clearance 0.1016)
			(thermal_gap 0.1016)
		)
		(pad "B66" thru_hole circle
			(at -4.499864 67.00012 270)
			(size 1.016 1.016)
			(drill 0.7112)
			(layers "*.Cu" "*.Mask")
			(remove_unused_layers no)
			(net "GND")
			(clearance 0.1016)
			(thermal_gap 0.1016)
		)
		(pad "B67" thru_hole circle
			(at -2.499868 67.999864 270)
			(size 1.016 1.016)
			(drill 0.7112)
			(layers "*.Cu" "*.Mask")
			(remove_unused_layers no)
			(net "Net_433")
			(clearance 0.1016)
			(thermal_gap 0.1016)
		)
		(pad "B68" thru_hole circle
			(at -4.499864 69.000116 270)
			(size 1.016 1.016)
			(drill 0.7112)
			(layers "*.Cu" "*.Mask")
			(remove_unused_layers no)
			(net "GND28")
			(clearance 0.1016)
			(thermal_gap 0.1016)
		)
		(pad "B69" thru_hole circle
			(at -2.499868 70.000114 270)
			(size 1.016 1.016)
			(drill 0.7112)
			(layers "*.Cu" "*.Mask")
			(remove_unused_layers no)
			(net "GND29")
			(clearance 0.1016)
			(thermal_gap 0.1016)
		)
		(pad "B70" thru_hole circle
			(at -4.499864 71.000112 270)
			(size 1.016 1.016)
			(drill 0.7112)
			(layers "*.Cu" "*.Mask")
			(remove_unused_layers no)
			(net "Net_432")
			(clearance 0.1016)
			(thermal_gap 0.1016)
		)
		(pad "B71" thru_hole circle
			(at -2.499868 72.00011 270)
			(size 1.016 1.016)
			(drill 0.7112)
			(layers "*.Cu" "*.Mask")
			(remove_unused_layers no)
			(net "GND")
			(clearance 0.1016)
			(thermal_gap 0.1016)
		)
		(pad "B72" thru_hole circle
			(at -4.499864 73.000108 270)
			(size 1.016 1.016)
			(drill 0.7112)
			(layers "*.Cu" "*.Mask")
			(remove_unused_layers no)
			(net "LAN1_P3_P")
			(clearance 0.1016)
			(thermal_gap 0.1016)
		)
	)
)
